(kicad_pcb
	(version 20260206)
	(generator "pcbnew")
	(generator_version "10.0")
	(general
		(thickness 1.6)
		(legacy_teardrops no)
	)
	(paper "A4")
	(title_block
		(title "baseboard — 13948-1b.1110WZS1818.brd")
		(comment 1 "Honey Badger (Wiwynn) / footprints 1922-1928 of 2523")
	)
	(layers
		(0 "F.Cu" signal "TOP")
		(4 "In1.Cu" signal "L2GND")
		(6 "In2.Cu" signal "L3")
		(8 "In3.Cu" signal "L4VCC")
		(10 "In4.Cu" signal "L5VCC")
		(12 "In5.Cu" signal "L6")
		(14 "In6.Cu" signal "L7GND")
		(2 "B.Cu" signal "BOTTOM")
		(9 "F.Adhes" user "F.Adhesive")
		(11 "B.Adhes" user "B.Adhesive")
		(13 "F.Paste" user "Package Geometry/Pastemask Top")
		(15 "B.Paste" user "Package Geometry/Pastemask Bottom")
		(5 "F.SilkS" user "Ref Des/Silkscreen Top")
		(7 "B.SilkS" user "Ref Des/Silkscreen Bottom")
		(1 "F.Mask" user "Board Geometry/Soldermask Top")
		(3 "B.Mask" user "Board Geometry/Soldermask Bottom")
		(17 "Dwgs.User" user "User.Drawings")
		(19 "Cmts.User" user "User.Comments")
		(21 "Eco1.User" user "User.Eco1")
		(23 "Eco2.User" user "User.Eco2")
		(25 "Edge.Cuts" user "Board Geometry/Outline")
		(27 "Margin" user)
		(31 "F.CrtYd" user "Package Geometry/Place Bound Top")
		(29 "B.CrtYd" user "Package Geometry/Place Bound Bottom")
		(35 "F.Fab" user "Ref Des/Assembly Top")
		(33 "B.Fab" user "Ref Des/Assembly Bottom")
	)
	(footprint ""
		(layer "B.Cu")
		(at 130.537966 -31.877 90)
		(property "Reference" "SQ3"
			(at 0 0 90)
			(layer "B.SilkS")
			(hide yes)
			(effects
				(font
					(size 1.27 1.27)
				)
				(justify mirror)
			)
		)
		(property "Value" "2N7002A-7-GP"
			(at -0.127 -8.9662 90)
			(unlocked yes)
			(layer "B.Fab")
			(hide yes)
			(effects
				(font
					(size 1.016 1.016)
					(thickness 0.1524)
				)
				(justify mirror)
			)
		)
		(property "Device Type" "SOT23DGS2D4H48"
			(at -0.127 -10.4902 90)
			(unlocked yes)
			(layer "B.Fab")
			(hide yes)
			(effects
				(font
					(size 1.016 1.016)
					(thickness 0.1524)
				)
				(justify mirror)
			)
		)
		(duplicate_pad_numbers_are_jumpers no)
		(fp_line
			(start 1.651 -1.778)
			(end 1.651 1.778)
			(stroke
				(width 0.1524)
				(type default)
			)
			(layer "B.SilkS")
		)
		(fp_line
			(start -1.651 -1.778)
			(end 1.651 -1.778)
			(stroke
				(width 0.1524)
				(type default)
			)
			(layer "B.SilkS")
		)
		(fp_line
			(start 1.651 1.778)
			(end -1.651 1.778)
			(stroke
				(width 0.1524)
				(type default)
			)
			(layer "B.SilkS")
		)
		(fp_line
			(start -1.651 1.778)
			(end -1.651 -1.778)
			(stroke
				(width 0.1524)
				(type default)
			)
			(layer "B.SilkS")
		)
		(fp_poly
			(pts
				(xy 1.778 1.8796) (xy 1.778 -1.8796) (xy -1.778 -1.8796) (xy -1.778 1.8796)
			)
			(stroke
				(width 0)
				(type default)
			)
			(fill no)
			(layer "B.CrtYd")
		)
		(fp_poly
			(pts
				(xy 1.778 1.8796) (xy 1.778 -1.8796) (xy -1.778 -1.8796) (xy -1.778 1.8796)
			)
			(stroke
				(width 0)
				(type default)
			)
			(fill no)
			(layer "B.Fab")
		)
		(pad "D" smd custom
			(at 0 -0.9525 270)
			(size 0.1905 0.1905)
			(layers "B.Cu" "B.Mask" "B.Paste")
			(net "SYS_RST")
			(options
				(clearance outline)
				(anchor circle)
			)
			(primitives
				(gr_poly
					(pts
						(arc
							(start -0.1778 -0.5715)
							(mid -0.321484 -0.511984)
							(end -0.381 -0.3683)
						)
						(arc
							(start -0.381 0.3683)
							(mid -0.321484 0.511984)
							(end -0.1778 0.5715)
						)
						(arc
							(start 0.1778 0.5715)
							(mid 0.321484 0.511984)
							(end 0.381 0.3683)
						)
						(arc
							(start 0.381 -0.3683)
							(mid 0.321484 -0.511984)
							(end 0.1778 -0.5715)
						)
					)
					(width 0)
					(fill yes)
				)
			)
		)
		(pad "G" smd custom
			(at 0.98425 0.9525 270)
			(size 0.1905 0.1905)
			(layers "B.Cu" "B.Mask" "B.Paste")
			(net "P3V3_STBY_B")
			(options
				(clearance outline)
				(anchor circle)
			)
			(primitives
				(gr_poly
					(pts
						(arc
							(start -0.1778 -0.5715)
							(mid -0.321484 -0.511984)
							(end -0.381 -0.3683)
						)
						(arc
							(start -0.381 0.3683)
							(mid -0.321484 0.511984)
							(end -0.1778 0.5715)
						)
						(arc
							(start 0.1778 0.5715)
							(mid 0.321484 0.511984)
							(end 0.381 0.3683)
						)
						(arc
							(start 0.381 -0.3683)
							(mid 0.321484 -0.511984)
							(end 0.1778 -0.5715)
						)
					)
					(width 0)
					(fill yes)
				)
			)
		)
		(pad "S" smd custom
			(at -0.98425 0.9525 270)
			(size 0.1905 0.1905)
			(layers "B.Cu" "B.Mask" "B.Paste")
			(net "GND")
			(options
				(clearance outline)
				(anchor circle)
			)
			(primitives
				(gr_poly
					(pts
						(arc
							(start -0.1778 -0.5715)
							(mid -0.321484 -0.511984)
							(end -0.381 -0.3683)
						)
						(arc
							(start -0.381 0.3683)
							(mid -0.321484 0.511984)
							(end -0.1778 0.5715)
						)
						(arc
							(start 0.1778 0.5715)
							(mid 0.321484 0.511984)
							(end 0.381 0.3683)
						)
						(arc
							(start 0.381 -0.3683)
							(mid 0.321484 -0.511984)
							(end 0.1778 -0.5715)
						)
					)
					(width 0)
					(fill yes)
				)
			)
		)
	)
	(footprint ""
		(layer "B.Cu")
		(at 328.295 -103.505 180)
		(property "Reference" "PC30"
			(at 0 0 0)
			(layer "B.SilkS")
			(hide yes)
			(effects
				(font
					(size 1.27 1.27)
				)
				(justify mirror)
			)
		)
		(property "Value" "SCD1U25V2KX-2-GP"
			(at -1.1811 -2.7051 180)
			(unlocked yes)
			(layer "B.Fab")
			(hide yes)
			(effects
				(font
					(size 1.016 1.016)
					(thickness 0.1524)
				)
				(justify mirror)
			)
		)
		(property "Device Type" "C402H22"
			(at -1.1811 -4.2291 180)
			(unlocked yes)
			(layer "B.Fab")
			(hide yes)
			(effects
				(font
					(size 1.016 1.016)
					(thickness 0.1524)
				)
				(justify mirror)
			)
		)
		(duplicate_pad_numbers_are_jumpers no)
		(fp_rect
			(start 0.4318 0.9525)
			(end -0.4318 -0.9525)
			(stroke
				(width 0)
				(type default)
			)
			(fill no)
			(layer "B.CrtYd")
		)
		(fp_rect
			(start 0.4318 0.9525)
			(end -0.4318 -0.9525)
			(stroke
				(width 0)
				(type default)
			)
			(fill no)
			(layer "B.Fab")
		)
		(pad "1" smd custom
			(at 0 -0.4445)
			(size 0.1524 0.1524)
			(layers "B.Cu" "B.Mask" "B.Paste")
			(net "P3V3_STBY")
			(options
				(clearance outline)
				(anchor circle)
			)
			(primitives
				(gr_poly
					(pts
						(arc
							(start 0.3048 0.2032)
							(mid 0.275042 0.275042)
							(end 0.2032 0.3048)
						)
						(arc
							(start -0.2032 0.3048)
							(mid -0.275042 0.275042)
							(end -0.3048 0.2032)
						)
						(arc
							(start -0.3048 -0.2032)
							(mid -0.275042 -0.275042)
							(end -0.2032 -0.3048)
						)
						(arc
							(start 0.2032 -0.3048)
							(mid 0.275042 -0.275042)
							(end 0.3048 -0.2032)
						)
					)
					(width 0)
					(fill yes)
				)
			)
		)
		(pad "2" smd custom
			(at 0 0.4445)
			(size 0.1524 0.1524)
			(layers "B.Cu" "B.Mask" "B.Paste")
			(net "P3V3_STBY_LL_R")
			(options
				(clearance outline)
				(anchor circle)
			)
			(primitives
				(gr_poly
					(pts
						(arc
							(start 0.3048 0.2032)
							(mid 0.275042 0.275042)
							(end 0.2032 0.3048)
						)
						(arc
							(start -0.2032 0.3048)
							(mid -0.275042 0.275042)
							(end -0.3048 0.2032)
						)
						(arc
							(start -0.3048 -0.2032)
							(mid -0.275042 -0.275042)
							(end -0.2032 -0.3048)
						)
						(arc
							(start 0.2032 -0.3048)
							(mid 0.275042 -0.275042)
							(end 0.3048 -0.2032)
						)
					)
					(width 0)
					(fill yes)
				)
			)
		)
	)
	(footprint ""
		(layer "B.Cu")
		(at 96.901 -230.124 -90)
		(property "Reference" "R667"
			(at 0 0 90)
			(layer "B.SilkS")
			(hide yes)
			(effects
				(font
					(size 1.27 1.27)
				)
				(justify mirror)
			)
		)
		(property "Value" "0R2J-2-GP"
			(at -0.064008 -3.993896 270)
			(unlocked yes)
			(layer "B.Fab")
			(hide yes)
			(effects
				(font
					(size 1.016 1.016)
					(thickness 0.1524)
				)
				(justify mirror)
			)
		)
		(property "Device Type" "R402H16"
			(at -0.064008 -5.517896 270)
			(unlocked yes)
			(layer "B.Fab")
			(hide yes)
			(effects
				(font
					(size 1.016 1.016)
					(thickness 0.1524)
				)
				(justify mirror)
			)
		)
		(duplicate_pad_numbers_are_jumpers no)
		(fp_line
			(start -0.508 -0.9398)
			(end 0.508 -0.9398)
			(stroke
				(width 0.1524)
				(type default)
			)
			(layer "B.SilkS")
		)
		(fp_line
			(start 0.508 -0.9398)
			(end 0.508 0.9398)
			(stroke
				(width 0.1524)
				(type default)
			)
			(layer "B.SilkS")
		)
		(fp_rect
			(start 0.508 0.9398)
			(end -0.508 -0.9398)
			(stroke
				(width 0)
				(type default)
			)
			(fill no)
			(layer "B.CrtYd")
		)
		(fp_rect
			(start 0.508 0.9398)
			(end -0.508 -0.9398)
			(stroke
				(width 0)
				(type default)
			)
			(fill no)
			(layer "B.Fab")
		)
		(pad "1" smd custom
			(at 0 -0.4445 90)
			(size 0.1397 0.1397)
			(layers "B.Cu" "B.Mask" "B.Paste")
			(net "SAS_FAULT_LED10")
			(options
				(clearance outline)
				(anchor circle)
			)
			(primitives
				(gr_poly
					(pts
						(arc
							(start -0.1778 0.2794)
							(mid -0.249642 0.249642)
							(end -0.2794 0.1778)
						)
						(arc
							(start -0.2794 -0.1778)
							(mid -0.249642 -0.249642)
							(end -0.1778 -0.2794)
						)
						(arc
							(start 0.1778 -0.2794)
							(mid 0.249642 -0.249642)
							(end 0.2794 -0.1778)
						)
						(arc
							(start 0.2794 0.1778)
							(mid 0.249642 0.249642)
							(end 0.1778 0.2794)
						)
					)
					(width 0)
					(fill yes)
				)
			)
		)
		(pad "2" smd custom
			(at 0 0.4445 90)
			(size 0.1397 0.1397)
			(layers "B.Cu" "B.Mask" "B.Paste")
			(net "SAS_HDD_LED_10")
			(options
				(clearance outline)
				(anchor circle)
			)
			(primitives
				(gr_poly
					(pts
						(arc
							(start -0.1778 0.2794)
							(mid -0.249642 0.249642)
							(end -0.2794 0.1778)
						)
						(arc
							(start -0.2794 -0.1778)
							(mid -0.249642 -0.249642)
							(end -0.1778 -0.2794)
						)
						(arc
							(start 0.1778 -0.2794)
							(mid 0.249642 -0.249642)
							(end 0.2794 -0.1778)
						)
						(arc
							(start 0.2794 0.1778)
							(mid 0.249642 0.249642)
							(end 0.1778 0.2794)
						)
					)
					(width 0)
					(fill yes)
				)
			)
		)
	)
	(footprint ""
		(layer "B.Cu")
		(at 318.008 -175.641 -90)
		(property "Reference" "R280"
			(at 0 0 90)
			(layer "B.SilkS")
			(hide yes)
			(effects
				(font
					(size 1.27 1.27)
				)
				(justify mirror)
			)
		)
		(property "Value" "0R2J-2-GP"
			(at -0.064008 -3.993896 270)
			(unlocked yes)
			(layer "B.Fab")
			(hide yes)
			(effects
				(font
					(size 1.016 1.016)
					(thickness 0.1524)
				)
				(justify mirror)
			)
		)
		(property "Device Type" "R402H16"
			(at -0.064008 -5.517896 270)
			(unlocked yes)
			(layer "B.Fab")
			(hide yes)
			(effects
				(font
					(size 1.016 1.016)
					(thickness 0.1524)
				)
				(justify mirror)
			)
		)
		(duplicate_pad_numbers_are_jumpers no)
		(fp_line
			(start -0.508 -0.9398)
			(end 0.508 -0.9398)
			(stroke
				(width 0.1524)
				(type default)
			)
			(layer "B.SilkS")
		)
		(fp_line
			(start 0.508 -0.9398)
			(end 0.508 0.9398)
			(stroke
				(width 0.1524)
				(type default)
			)
			(layer "B.SilkS")
		)
		(fp_rect
			(start 0.508 0.9398)
			(end -0.508 -0.9398)
			(stroke
				(width 0)
				(type default)
			)
			(fill no)
			(layer "B.CrtYd")
		)
		(fp_rect
			(start 0.508 0.9398)
			(end -0.508 -0.9398)
			(stroke
				(width 0)
				(type default)
			)
			(fill no)
			(layer "B.Fab")
		)
		(pad "1" smd custom
			(at 0 -0.4445 90)
			(size 0.1397 0.1397)
			(layers "B.Cu" "B.Mask" "B.Paste")
			(net "BMC_TXD5")
			(options
				(clearance outline)
				(anchor circle)
			)
			(primitives
				(gr_poly
					(pts
						(arc
							(start -0.1778 0.2794)
							(mid -0.249642 0.249642)
							(end -0.2794 0.1778)
						)
						(arc
							(start -0.2794 -0.1778)
							(mid -0.249642 -0.249642)
							(end -0.1778 -0.2794)
						)
						(arc
							(start 0.1778 -0.2794)
							(mid 0.249642 -0.249642)
							(end 0.2794 -0.1778)
						)
						(arc
							(start 0.2794 0.1778)
							(mid 0.249642 0.249642)
							(end 0.1778 0.2794)
						)
					)
					(width 0)
					(fill yes)
				)
			)
		)
		(pad "2" smd custom
			(at 0 0.4445 90)
			(size 0.1397 0.1397)
			(layers "B.Cu" "B.Mask" "B.Paste")
			(net "BMC_TXD5_R")
			(options
				(clearance outline)
				(anchor circle)
			)
			(primitives
				(gr_poly
					(pts
						(arc
							(start -0.1778 0.2794)
							(mid -0.249642 0.249642)
							(end -0.2794 0.1778)
						)
						(arc
							(start -0.2794 -0.1778)
							(mid -0.249642 -0.249642)
							(end -0.1778 -0.2794)
						)
						(arc
							(start 0.1778 -0.2794)
							(mid 0.249642 -0.249642)
							(end 0.2794 -0.1778)
						)
						(arc
							(start 0.2794 0.1778)
							(mid 0.249642 0.249642)
							(end 0.1778 0.2794)
						)
					)
					(width 0)
					(fill yes)
				)
			)
		)
	)
	(footprint ""
		(layer "B.Cu")
		(at 199.898 -102.489)
		(property "Reference" "PC233"
			(at 0 0 0)
			(layer "B.SilkS")
			(hide yes)
			(effects
				(font
					(size 1.27 1.27)
				)
				(justify mirror)
			)
		)
		(property "Value" "SCD1U50V3KX-GP"
			(at 0 -2.8194 0)
			(unlocked yes)
			(layer "B.Fab")
			(hide yes)
			(effects
				(font
					(size 1.016 1.016)
					(thickness 0.1524)
				)
				(justify mirror)
			)
		)
		(property "Device Type" "C603H36"
			(at 0 -4.3434 0)
			(unlocked yes)
			(layer "B.Fab")
			(hide yes)
			(effects
				(font
					(size 1.016 1.016)
					(thickness 0.1524)
				)
				(justify mirror)
			)
		)
		(duplicate_pad_numbers_are_jumpers no)
		(fp_line
			(start -0.508 0)
			(end 0.508 0)
			(stroke
				(width 0.2032)
				(type default)
			)
			(layer "B.SilkS")
		)
		(fp_rect
			(start 0.5842 1.3335)
			(end -0.5842 -1.3335)
			(stroke
				(width 0)
				(type default)
			)
			(fill no)
			(layer "B.CrtYd")
		)
		(fp_rect
			(start 0.5842 1.3335)
			(end -0.5842 -1.3335)
			(stroke
				(width 0)
				(type default)
			)
			(fill no)
			(layer "B.Fab")
		)
		(pad "1" smd custom
			(at 0 -0.762 180)
			(size 0.2159 0.2159)
			(layers "B.Cu" "B.Mask" "B.Paste")
			(net "P1V5_E_VFB_R")
			(options
				(clearance outline)
				(anchor circle)
			)
			(primitives
				(gr_poly
					(pts
						(arc
							(start -0.3302 0.4318)
							(mid -0.402042 0.402042)
							(end -0.4318 0.3302)
						)
						(arc
							(start -0.4318 -0.3302)
							(mid -0.402042 -0.402042)
							(end -0.3302 -0.4318)
						)
						(arc
							(start 0.3302 -0.4318)
							(mid 0.402042 -0.402042)
							(end 0.4318 -0.3302)
						)
						(arc
							(start 0.4318 0.3302)
							(mid 0.402042 0.402042)
							(end 0.3302 0.4318)
						)
					)
					(width 0)
					(fill yes)
				)
			)
		)
		(pad "2" smd custom
			(at 0 0.762 180)
			(size 0.2159 0.2159)
			(layers "B.Cu" "B.Mask" "B.Paste")
			(net "P1V5_E")
			(options
				(clearance outline)
				(anchor circle)
			)
			(primitives
				(gr_poly
					(pts
						(arc
							(start -0.3302 0.4318)
							(mid -0.402042 0.402042)
							(end -0.4318 0.3302)
						)
						(arc
							(start -0.4318 -0.3302)
							(mid -0.402042 -0.402042)
							(end -0.3302 -0.4318)
						)
						(arc
							(start 0.3302 -0.4318)
							(mid 0.402042 -0.402042)
							(end 0.4318 -0.3302)
						)
						(arc
							(start 0.4318 0.3302)
							(mid 0.402042 0.402042)
							(end 0.3302 0.4318)
						)
					)
					(width 0)
					(fill yes)
				)
			)
		)
	)
	(footprint ""
		(layer "B.Cu")
		(at 102.343966 -40.386)
		(property "Reference" "SC1062"
			(at 0 0 0)
			(layer "B.SilkS")
			(hide yes)
			(effects
				(font
					(size 1.27 1.27)
				)
				(justify mirror)
			)
		)
		(property "Value" "SCD1U16V2KX-3GP"
			(at -1.1811 -2.7051 0)
			(unlocked yes)
			(layer "B.Fab")
			(hide yes)
			(effects
				(font
					(size 1.016 1.016)
					(thickness 0.1524)
				)
				(justify mirror)
			)
		)
		(property "Device Type" "C402H22"
			(at -1.1811 -4.2291 0)
			(unlocked yes)
			(layer "B.Fab")
			(hide yes)
			(effects
				(font
					(size 1.016 1.016)
					(thickness 0.1524)
				)
				(justify mirror)
			)
		)
		(duplicate_pad_numbers_are_jumpers no)
		(fp_rect
			(start 0.4318 0.9525)
			(end -0.4318 -0.9525)
			(stroke
				(width 0)
				(type default)
			)
			(fill no)
			(layer "B.CrtYd")
		)
		(fp_rect
			(start 0.4318 0.9525)
			(end -0.4318 -0.9525)
			(stroke
				(width 0)
				(type default)
			)
			(fill no)
			(layer "B.Fab")
		)
		(pad "1" smd custom
			(at 0 -0.4445 180)
			(size 0.1524 0.1524)
			(layers "B.Cu" "B.Mask" "B.Paste")
			(net "P0V955_C")
			(options
				(clearance outline)
				(anchor circle)
			)
			(primitives
				(gr_poly
					(pts
						(arc
							(start 0.3048 0.2032)
							(mid 0.275042 0.275042)
							(end 0.2032 0.3048)
						)
						(arc
							(start -0.2032 0.3048)
							(mid -0.275042 0.275042)
							(end -0.3048 0.2032)
						)
						(arc
							(start -0.3048 -0.2032)
							(mid -0.275042 -0.275042)
							(end -0.2032 -0.3048)
						)
						(arc
							(start 0.2032 -0.3048)
							(mid 0.275042 -0.275042)
							(end 0.3048 -0.2032)
						)
					)
					(width 0)
					(fill yes)
				)
			)
		)
		(pad "2" smd custom
			(at 0 0.4445 180)
			(size 0.1524 0.1524)
			(layers "B.Cu" "B.Mask" "B.Paste")
			(net "GND")
			(options
				(clearance outline)
				(anchor circle)
			)
			(primitives
				(gr_poly
					(pts
						(arc
							(start 0.3048 0.2032)
							(mid 0.275042 0.275042)
							(end 0.2032 0.3048)
						)
						(arc
							(start -0.2032 0.3048)
							(mid -0.275042 0.275042)
							(end -0.3048 0.2032)
						)
						(arc
							(start -0.3048 -0.2032)
							(mid -0.275042 -0.275042)
							(end -0.2032 -0.3048)
						)
						(arc
							(start 0.2032 -0.3048)
							(mid 0.275042 -0.275042)
							(end 0.3048 -0.2032)
						)
					)
					(width 0)
					(fill yes)
				)
			)
		)
	)
	(footprint ""
		(layer "B.Cu")
		(at 117.38737 -79.9084 -90)
		(property "Reference" "SL13"
			(at 0 0 90)
			(layer "B.SilkS")
			(hide yes)
			(effects
				(font
					(size 1.27 1.27)
				)
				(justify mirror)
			)
		)
		(property "Value" "MPZ2012S601AT-GP"
			(at 0 -4.2418 270)
			(unlocked yes)
			(layer "B.Fab")
			(hide yes)
			(effects
				(font
					(size 1.016 1.016)
					(thickness 0.1524)
				)
				(justify mirror)
			)
		)
		(property "Device Type" "L805H42"
			(at 0 -5.7912 270)
			(unlocked yes)
			(layer "B.Fab")
			(hide yes)
			(effects
				(font
					(size 1.016 1.016)
					(thickness 0.1524)
				)
				(justify mirror)
			)
		)
		(duplicate_pad_numbers_are_jumpers no)
		(fp_line
			(start -0.889 1.7018)
			(end 0.889 1.7018)
			(stroke
				(width 0.1524)
				(type default)
			)
			(layer "B.SilkS")
		)
		(fp_line
			(start 0.889 1.7018)
			(end 0.889 -1.7018)
			(stroke
				(width 0.1524)
				(type default)
			)
			(layer "B.SilkS")
		)
		(fp_line
			(start -0.889 -1.7018)
			(end -0.889 1.7018)
			(stroke
				(width 0.1524)
				(type default)
			)
			(layer "B.SilkS")
		)
		(fp_line
			(start 0.889 -1.7018)
			(end -0.889 -1.7018)
			(stroke
				(width 0.1524)
				(type default)
			)
			(layer "B.SilkS")
		)
		(fp_rect
			(start 0.9652 1.778)
			(end -0.9652 -1.778)
			(stroke
				(width 0)
				(type default)
			)
			(fill no)
			(layer "B.CrtYd")
		)
		(fp_rect
			(start 0.9652 1.778)
			(end -0.9652 -1.778)
			(stroke
				(width 0)
				(type default)
			)
			(fill no)
			(layer "B.Fab")
		)
		(pad "1" smd rect
			(at 0 -0.9652 90)
			(size 1.397 1.143)
			(layers "B.Cu" "B.Mask" "B.Paste")
			(net "XTAL_VDDA18")
		)
		(pad "2" smd rect
			(at 0 0.9652 90)
			(size 1.397 1.143)
			(layers "B.Cu" "B.Mask" "B.Paste")
			(net "P1V8_E")
		)
	)
)
